(kicad_pcb
	(version 20260206)
	(generator "pcbnew")
	(generator_version "10.0")
	(general
		(thickness 1.6)
		(legacy_teardrops no)
	)
	(paper "A4")
	(title_block
		(title "Wiwynn_Tioga_Pass_MB.brd")
		(comment 1 "Tioga Pass / footprints 1835-1841 of 4770")
	)
	(layers
		(0 "F.Cu" signal "TOP")
		(4 "In1.Cu" signal "L2GND")
		(6 "In2.Cu" signal "L3")
		(8 "In3.Cu" signal "L4GND")
		(10 "In4.Cu" signal "L5")
		(12 "In5.Cu" signal "L6GND")
		(14 "In6.Cu" signal "L7VCC")
		(16 "In7.Cu" signal "L8VCC")
		(18 "In8.Cu" signal "L9GND")
		(20 "In9.Cu" signal "L10")
		(22 "In10.Cu" signal "L11GND")
		(24 "In11.Cu" signal "L12")
		(26 "In12.Cu" signal "L13GND")
		(2 "B.Cu" signal "BOTTOM")
		(9 "F.Adhes" user "F.Adhesive")
		(11 "B.Adhes" user "B.Adhesive")
		(13 "F.Paste" user "Package Geometry/Pastemask Top")
		(15 "B.Paste" user "Package Geometry/Pastemask Bottom")
		(5 "F.SilkS" user "Ref Des/Silkscreen Top")
		(7 "B.SilkS" user "Ref Des/Silkscreen Bottom")
		(1 "F.Mask" user "Board Geometry/Soldermask Top")
		(3 "B.Mask" user "Board Geometry/Soldermask Bottom")
		(17 "Dwgs.User" user "User.Drawings")
		(19 "Cmts.User" user "User.Comments")
		(21 "Eco1.User" user "User.Eco1")
		(23 "Eco2.User" user "User.Eco2")
		(25 "Edge.Cuts" user "Board Geometry/Outline")
		(27 "Margin" user)
		(31 "F.CrtYd" user "Package Geometry/Place Bound Top")
		(29 "B.CrtYd" user "Package Geometry/Place Bound Bottom")
		(35 "F.Fab" user "Ref Des/Assembly Top")
		(33 "B.Fab" user "Ref Des/Assembly Bottom")
	)
	(footprint ""
		(layer "F.Cu")
		(at 408.8765 -105.664 -90)
		(property "Reference" "R8C17"
			(at 0 0 270)
			(layer "F.SilkS")
			(hide yes)
			(effects
				(font
					(size 1.27 1.27)
				)
			)
		)
		(property "Value" ""
			(at 0 0 270)
			(layer "F.Fab")
			(effects
				(font
					(size 1.27 1.27)
				)
			)
		)
		(duplicate_pad_numbers_are_jumpers no)
		(fp_poly
			(pts
				(xy -0.2794 -0.1016) (xy 0.2794 -0.1016) (xy 0.2794 0.9906) (xy -0.2794 0.9906)
			)
			(stroke
				(width 0)
				(type default)
			)
			(fill no)
			(layer "F.CrtYd")
		)
		(fp_line
			(start -0.2794 0.9906)
			(end 0.2794 0.9906)
			(stroke
				(width 0.1)
				(type default)
			)
			(layer "F.Fab")
		)
		(fp_line
			(start 0.2794 0.9906)
			(end 0.2794 -0.1016)
			(stroke
				(width 0.1)
				(type default)
			)
			(layer "F.Fab")
		)
		(fp_line
			(start -0.2794 -0.1016)
			(end -0.2794 0.9906)
			(stroke
				(width 0.1)
				(type default)
			)
			(layer "F.Fab")
		)
		(fp_line
			(start 0.2794 -0.1016)
			(end -0.2794 -0.1016)
			(stroke
				(width 0.1)
				(type default)
			)
			(layer "F.Fab")
		)
		(pad "1" smd rect
			(at 0 0 270)
			(size 0.508 0.508)
			(layers "F.Cu" "F.Mask" "F.Paste")
			(net "PU_PCH_TLS_ENABLE_STRAP")
		)
		(pad "2" smd rect
			(at 0 0.889 270)
			(size 0.508 0.508)
			(layers "F.Cu" "F.Mask" "F.Paste")
			(net "GND")
		)
		(zone
			(layer "F.Cu")
			(hatch none 0.5)
			(connect_pads
				(clearance 0)
			)
			(min_thickness 0.25)
			(keepout
				(tracks not_allowed)
				(vias allowed)
				(pads allowed)
				(copperpour not_allowed)
				(footprints allowed)
			)
			(placement
				(enabled no)
				(sheetname "")
			)
			(fill
				(thermal_gap 0.5)
				(thermal_bridge_width 0.5)
				(island_removal_mode 0)
			)
			(polygon
				(pts
					(xy 408.2415 -105.918) (xy 408.2415 -105.41) (xy 408.6225 -105.41) (xy 408.6225 -105.918)
				)
			)
		)
		(zone
			(layer "F.Cu")
			(hatch none 0.5)
			(connect_pads
				(clearance 0)
			)
			(min_thickness 0.25)
			(keepout
				(tracks allowed)
				(vias not_allowed)
				(pads allowed)
				(copperpour not_allowed)
				(footprints allowed)
			)
			(placement
				(enabled no)
				(sheetname "")
			)
			(fill
				(thermal_gap 0.5)
				(thermal_bridge_width 0.5)
				(island_removal_mode 0)
			)
			(polygon
				(pts
					(xy 408.6225 -105.918) (xy 408.6225 -105.41) (xy 408.2415 -105.41) (xy 408.2415 -105.918)
				)
			)
		)
	)
	(footprint ""
		(layer "F.Cu")
		(at 259.1054 -149.7838 90)
		(property "Reference" "C5A10"
			(at 0 0 90)
			(layer "F.SilkS")
			(hide yes)
			(effects
				(font
					(size 1.27 1.27)
				)
			)
		)
		(property "Value" ""
			(at 0 0 90)
			(layer "F.Fab")
			(effects
				(font
					(size 1.27 1.27)
				)
			)
		)
		(duplicate_pad_numbers_are_jumpers no)
		(fp_rect
			(start -0.7239 -0.2159)
			(end 0.7239 1.9939)
			(stroke
				(width 0)
				(type default)
			)
			(fill no)
			(layer "F.CrtYd")
		)
		(fp_line
			(start 0.7239 -0.2159)
			(end -0.7239 -0.2159)
			(stroke
				(width 0.1)
				(type default)
			)
			(layer "F.Fab")
		)
		(fp_line
			(start -0.7239 -0.2159)
			(end -0.7239 1.9939)
			(stroke
				(width 0.1)
				(type default)
			)
			(layer "F.Fab")
		)
		(fp_line
			(start 0.7239 1.9939)
			(end 0.7239 -0.2159)
			(stroke
				(width 0.1)
				(type default)
			)
			(layer "F.Fab")
		)
		(fp_line
			(start -0.7239 1.9939)
			(end 0.7239 1.9939)
			(stroke
				(width 0.1)
				(type default)
			)
			(layer "F.Fab")
		)
		(pad "1" smd rect
			(at 0 0 90)
			(size 1.27 1.016)
			(layers "F.Cu" "F.Mask" "F.Paste")
			(net "PVDDQ_DEF")
		)
		(pad "2" smd rect
			(at 0 1.778 90)
			(size 1.27 1.016)
			(layers "F.Cu" "F.Mask" "F.Paste")
			(net "GND")
		)
		(zone
			(layer "F.Cu")
			(hatch none 0.5)
			(connect_pads
				(clearance 0)
			)
			(min_thickness 0.25)
			(keepout
				(tracks not_allowed)
				(vias allowed)
				(pads allowed)
				(copperpour not_allowed)
				(footprints allowed)
			)
			(placement
				(enabled no)
				(sheetname "")
			)
			(fill
				(thermal_gap 0.5)
				(thermal_bridge_width 0.5)
				(island_removal_mode 0)
			)
			(polygon
				(pts
					(xy 259.6134 -149.1488) (xy 260.3754 -149.1488) (xy 260.3754 -150.4188) (xy 259.6134 -150.4188)
				)
			)
		)
	)
	(footprint ""
		(layer "F.Cu")
		(at 30.528768 -149.6568 90)
		(property "Reference" "C1A5"
			(at 0 0 90)
			(layer "F.SilkS")
			(hide yes)
			(effects
				(font
					(size 1.27 1.27)
				)
			)
		)
		(property "Value" ""
			(at 0 0 90)
			(layer "F.Fab")
			(effects
				(font
					(size 1.27 1.27)
				)
			)
		)
		(duplicate_pad_numbers_are_jumpers no)
		(fp_poly
			(pts
				(xy 0.3048 -0.1016) (xy 0.3048 0.9906) (xy -0.3048 0.9906) (xy -0.3048 -0.1016)
			)
			(stroke
				(width 0)
				(type default)
			)
			(fill no)
			(layer "F.CrtYd")
		)
		(fp_line
			(start 0.3048 -0.1016)
			(end -0.3048 -0.1016)
			(stroke
				(width 0.1)
				(type default)
			)
			(layer "F.Fab")
		)
		(fp_line
			(start -0.3048 -0.1016)
			(end -0.3048 0.9906)
			(stroke
				(width 0.1)
				(type default)
			)
			(layer "F.Fab")
		)
		(fp_line
			(start 0.3048 0.9906)
			(end 0.3048 -0.1016)
			(stroke
				(width 0.1)
				(type default)
			)
			(layer "F.Fab")
		)
		(fp_line
			(start -0.3048 0.9906)
			(end 0.3048 0.9906)
			(stroke
				(width 0.1)
				(type default)
			)
			(layer "F.Fab")
		)
		(pad "1" smd rect
			(at 0 0 90)
			(size 0.508 0.508)
			(layers "F.Cu" "F.Mask" "F.Paste")
			(net "M_M_VREF")
		)
		(pad "2" smd rect
			(at 0 0.889 90)
			(size 0.508 0.508)
			(layers "F.Cu" "F.Mask" "F.Paste")
			(net "GND")
		)
		(zone
			(layer "F.Cu")
			(hatch none 0.5)
			(connect_pads
				(clearance 0)
			)
			(min_thickness 0.25)
			(keepout
				(tracks allowed)
				(vias not_allowed)
				(pads allowed)
				(copperpour not_allowed)
				(footprints allowed)
			)
			(placement
				(enabled no)
				(sheetname "")
			)
			(fill
				(thermal_gap 0.5)
				(thermal_bridge_width 0.5)
				(island_removal_mode 0)
			)
			(polygon
				(pts
					(xy 30.782768 -149.4028) (xy 30.782768 -149.9108) (xy 31.163768 -149.9108) (xy 31.163768 -149.4028)
				)
			)
		)
		(zone
			(layer "F.Cu")
			(hatch none 0.5)
			(connect_pads
				(clearance 0)
			)
			(min_thickness 0.25)
			(keepout
				(tracks not_allowed)
				(vias allowed)
				(pads allowed)
				(copperpour not_allowed)
				(footprints allowed)
			)
			(placement
				(enabled no)
				(sheetname "")
			)
			(fill
				(thermal_gap 0.5)
				(thermal_bridge_width 0.5)
				(island_removal_mode 0)
			)
			(polygon
				(pts
					(xy 31.163768 -149.4028) (xy 31.163768 -149.9108) (xy 30.782768 -149.9108) (xy 30.782768 -149.4028)
				)
			)
		)
	)
	(footprint ""
		(layer "F.Cu")
		(at 414.528 -16.383)
		(property "Reference" "S8E1"
			(at -2.31267 3.3274 270)
			(unlocked yes)
			(layer "F.SilkS")
			(effects
				(font
					(size 0.7874 0.5842)
					(thickness 0.1524)
				)
			)
		)
		(property "Value" ""
			(at 0 0 0)
			(layer "F.Fab")
			(effects
				(font
					(size 1.27 1.27)
				)
			)
		)
		(duplicate_pad_numbers_are_jumpers no)
		(fp_line
			(start -1.6256 0.0381)
			(end -0.954278 0.0381)
			(stroke
				(width 0.1524)
				(type default)
			)
			(layer "F.SilkS")
		)
		(fp_line
			(start -1.6256 4.2799)
			(end -1.6256 0.0381)
			(stroke
				(width 0.1524)
				(type default)
			)
			(layer "F.SilkS")
		)
		(fp_line
			(start -1.6256 4.2799)
			(end -0.954024 4.2799)
			(stroke
				(width 0.1524)
				(type default)
			)
			(layer "F.SilkS")
		)
		(fp_line
			(start 1.6256 0.0381)
			(end 0.953262 0.0381)
			(stroke
				(width 0.1524)
				(type default)
			)
			(layer "F.SilkS")
		)
		(fp_line
			(start 1.6256 0.0381)
			(end 1.6256 4.2799)
			(stroke
				(width 0.1524)
				(type default)
			)
			(layer "F.SilkS")
		)
		(fp_line
			(start 1.6256 4.2799)
			(end 0.954024 4.2799)
			(stroke
				(width 0.1524)
				(type default)
			)
			(layer "F.SilkS")
		)
		(fp_circle
			(center -1.177036 -0.999998)
			(end -1.050036 -0.999998)
			(stroke
				(width 0.254)
				(type default)
			)
			(fill no)
			(layer "F.SilkS")
		)
		(fp_poly
			(pts
				(xy -1.6256 0.0381) (xy -1.6256 4.2799) (xy 1.6256 4.2799) (xy 1.6256 0.0381)
			)
			(stroke
				(width 0)
				(type default)
			)
			(fill no)
			(layer "F.CrtYd")
		)
		(fp_line
			(start -1.6256 0.0381)
			(end 1.6256 0.0381)
			(stroke
				(width 0.1)
				(type default)
			)
			(layer "F.Fab")
		)
		(fp_line
			(start -1.6256 4.2799)
			(end -1.6256 0.0381)
			(stroke
				(width 0.1)
				(type default)
			)
			(layer "F.Fab")
		)
		(fp_line
			(start 1.6256 0.0381)
			(end 1.6256 4.2799)
			(stroke
				(width 0.1)
				(type default)
			)
			(layer "F.Fab")
		)
		(fp_line
			(start 1.6256 4.2799)
			(end -1.6256 4.2799)
			(stroke
				(width 0.1)
				(type default)
			)
			(layer "F.Fab")
		)
		(fp_circle
			(center -1.208786 -1.23698)
			(end -1.081786 -1.23698)
			(stroke
				(width 0.254)
				(type default)
			)
			(fill no)
			(layer "F.Fab")
		)
		(pad "1" smd rect
			(at 0 0)
			(size 1.2446 1.7272)
			(layers "F.Cu" "F.Mask" "F.Paste")
			(net "GND")
		)
		(pad "2" smd rect
			(at 0 4.318)
			(size 1.2446 1.7272)
			(layers "F.Cu" "F.Mask" "F.Paste")
			(net "FP_NMI_BTN_OUT_R_N")
		)
	)
	(footprint ""
		(layer "F.Cu")
		(at 17.9832 -79.6417 180)
		(property "Reference" "R1D26"
			(at 0 0 180)
			(layer "F.SilkS")
			(hide yes)
			(effects
				(font
					(size 1.27 1.27)
				)
			)
		)
		(property "Value" ""
			(at 0 0 180)
			(layer "F.Fab")
			(effects
				(font
					(size 1.27 1.27)
				)
			)
		)
		(duplicate_pad_numbers_are_jumpers no)
		(fp_poly
			(pts
				(xy -0.2794 -0.1016) (xy 0.2794 -0.1016) (xy 0.2794 0.9906) (xy -0.2794 0.9906)
			)
			(stroke
				(width 0)
				(type default)
			)
			(fill no)
			(layer "F.CrtYd")
		)
		(fp_line
			(start 0.2794 0.9906)
			(end 0.2794 -0.1016)
			(stroke
				(width 0.1)
				(type default)
			)
			(layer "F.Fab")
		)
		(fp_line
			(start 0.2794 -0.1016)
			(end -0.2794 -0.1016)
			(stroke
				(width 0.1)
				(type default)
			)
			(layer "F.Fab")
		)
		(fp_line
			(start -0.2794 0.9906)
			(end 0.2794 0.9906)
			(stroke
				(width 0.1)
				(type default)
			)
			(layer "F.Fab")
		)
		(fp_line
			(start -0.2794 -0.1016)
			(end -0.2794 0.9906)
			(stroke
				(width 0.1)
				(type default)
			)
			(layer "F.Fab")
		)
		(pad "1" smd rect
			(at 0 0 180)
			(size 0.508 0.508)
			(layers "F.Cu" "F.Mask" "F.Paste")
			(net "IRQ_SML1_PMBUS_ALERT_R_N")
		)
		(pad "2" smd rect
			(at 0 0.889 180)
			(size 0.508 0.508)
			(layers "F.Cu" "F.Mask" "F.Paste")
			(net "IRQ_SML1_PMBUS_ALERT_N")
		)
		(zone
			(layer "F.Cu")
			(hatch none 0.5)
			(connect_pads
				(clearance 0)
			)
			(min_thickness 0.25)
			(keepout
				(tracks not_allowed)
				(vias allowed)
				(pads allowed)
				(copperpour not_allowed)
				(footprints allowed)
			)
			(placement
				(enabled no)
				(sheetname "")
			)
			(fill
				(thermal_gap 0.5)
				(thermal_bridge_width 0.5)
				(island_removal_mode 0)
			)
			(polygon
				(pts
					(xy 18.2372 -80.2767) (xy 17.7292 -80.2767) (xy 17.7292 -79.8957) (xy 18.2372 -79.8957)
				)
			)
		)
		(zone
			(layer "F.Cu")
			(hatch none 0.5)
			(connect_pads
				(clearance 0)
			)
			(min_thickness 0.25)
			(keepout
				(tracks allowed)
				(vias not_allowed)
				(pads allowed)
				(copperpour not_allowed)
				(footprints allowed)
			)
			(placement
				(enabled no)
				(sheetname "")
			)
			(fill
				(thermal_gap 0.5)
				(thermal_bridge_width 0.5)
				(island_removal_mode 0)
			)
			(polygon
				(pts
					(xy 18.2372 -79.8957) (xy 17.7292 -79.8957) (xy 17.7292 -80.2767) (xy 18.2372 -80.2767)
				)
			)
		)
	)
	(footprint ""
		(layer "F.Cu")
		(at 418.554408 -48.953166)
		(property "Reference" "R1T15"
			(at -0.8382 -0.67818 0)
			(unlocked yes)
			(layer "F.SilkS")
			(effects
				(font
					(size 0.4064 0.254)
					(thickness 0.1524)
				)
				(justify left)
			)
		)
		(property "Value" ""
			(at 0 0 0)
			(layer "F.Fab")
			(effects
				(font
					(size 1.27 1.27)
				)
			)
		)
		(duplicate_pad_numbers_are_jumpers no)
		(fp_poly
			(pts
				(xy -0.2794 -0.1016) (xy 0.2794 -0.1016) (xy 0.2794 0.9906) (xy -0.2794 0.9906)
			)
			(stroke
				(width 0)
				(type default)
			)
			(fill no)
			(layer "F.CrtYd")
		)
		(fp_line
			(start -0.2794 -0.1016)
			(end -0.2794 0.9906)
			(stroke
				(width 0.1)
				(type default)
			)
			(layer "F.Fab")
		)
		(fp_line
			(start -0.2794 0.9906)
			(end 0.2794 0.9906)
			(stroke
				(width 0.1)
				(type default)
			)
			(layer "F.Fab")
		)
		(fp_line
			(start 0.2794 -0.1016)
			(end -0.2794 -0.1016)
			(stroke
				(width 0.1)
				(type default)
			)
			(layer "F.Fab")
		)
		(fp_line
			(start 0.2794 0.9906)
			(end 0.2794 -0.1016)
			(stroke
				(width 0.1)
				(type default)
			)
			(layer "F.Fab")
		)
		(pad "1" smd rect
			(at 0 0)
			(size 0.508 0.508)
			(layers "F.Cu" "F.Mask" "F.Paste")
			(net "FM_BMC_ONCTL_N")
		)
		(pad "2" smd rect
			(at 0 0.889)
			(size 0.508 0.508)
			(layers "F.Cu" "F.Mask" "F.Paste")
			(net "FM_BMC_ONCTL_R_N")
		)
		(zone
			(layer "F.Cu")
			(hatch none 0.5)
			(connect_pads
				(clearance 0)
			)
			(min_thickness 0.25)
			(keepout
				(tracks allowed)
				(vias not_allowed)
				(pads allowed)
				(copperpour not_allowed)
				(footprints allowed)
			)
			(placement
				(enabled no)
				(sheetname "")
			)
			(fill
				(thermal_gap 0.5)
				(thermal_bridge_width 0.5)
				(island_removal_mode 0)
			)
			(polygon
				(pts
					(xy 418.300408 -48.699166) (xy 418.808408 -48.699166) (xy 418.808408 -48.318166) (xy 418.300408 -48.318166)
				)
			)
		)
		(zone
			(layer "F.Cu")
			(hatch none 0.5)
			(connect_pads
				(clearance 0)
			)
			(min_thickness 0.25)
			(keepout
				(tracks not_allowed)
				(vias allowed)
				(pads allowed)
				(copperpour not_allowed)
				(footprints allowed)
			)
			(placement
				(enabled no)
				(sheetname "")
			)
			(fill
				(thermal_gap 0.5)
				(thermal_bridge_width 0.5)
				(island_removal_mode 0)
			)
			(polygon
				(pts
					(xy 418.300408 -48.318166) (xy 418.808408 -48.318166) (xy 418.808408 -48.699166) (xy 418.300408 -48.699166)
				)
			)
		)
	)
	(footprint ""
		(layer "F.Cu")
		(at 320.6115 -123.317 90)
		(property "Reference" "C6B5"
			(at -0.8382 -0.67818 90)
			(unlocked yes)
			(layer "F.SilkS")
			(effects
				(font
					(size 0.4064 0.254)
					(thickness 0.1524)
				)
				(justify left)
			)
		)
		(property "Value" ""
			(at 0 0 90)
			(layer "F.Fab")
			(effects
				(font
					(size 1.27 1.27)
				)
			)
		)
		(duplicate_pad_numbers_are_jumpers no)
		(fp_poly
			(pts
				(xy 0.3048 -0.1016) (xy 0.3048 0.9906) (xy -0.3048 0.9906) (xy -0.3048 -0.1016)
			)
			(stroke
				(width 0)
				(type default)
			)
			(fill no)
			(layer "F.CrtYd")
		)
		(fp_line
			(start 0.3048 -0.1016)
			(end -0.3048 -0.1016)
			(stroke
				(width 0.1)
				(type default)
			)
			(layer "F.Fab")
		)
		(fp_line
			(start -0.3048 -0.1016)
			(end -0.3048 0.9906)
			(stroke
				(width 0.1)
				(type default)
			)
			(layer "F.Fab")
		)
		(fp_line
			(start 0.3048 0.9906)
			(end 0.3048 -0.1016)
			(stroke
				(width 0.1)
				(type default)
			)
			(layer "F.Fab")
		)
		(fp_line
			(start -0.3048 0.9906)
			(end 0.3048 0.9906)
			(stroke
				(width 0.1)
				(type default)
			)
			(layer "F.Fab")
		)
		(pad "1" smd rect
			(at 0 0 90)
			(size 0.508 0.508)
			(layers "F.Cu" "F.Mask" "F.Paste")
			(net "P3E_CPU0_PE1_PCH_TXP<15>")
		)
		(pad "2" smd rect
			(at 0 0.889 90)
			(size 0.508 0.508)
			(layers "F.Cu" "F.Mask" "F.Paste")
			(net "P3E_CPU0_PE1_PCH_C_TXP<15>")
		)
		(zone
			(layer "F.Cu")
			(hatch none 0.5)
			(connect_pads
				(clearance 0)
			)
			(min_thickness 0.25)
			(keepout
				(tracks allowed)
				(vias not_allowed)
				(pads allowed)
				(copperpour not_allowed)
				(footprints allowed)
			)
			(placement
				(enabled no)
				(sheetname "")
			)
			(fill
				(thermal_gap 0.5)
				(thermal_bridge_width 0.5)
				(island_removal_mode 0)
			)
			(polygon
				(pts
					(xy 320.8655 -123.063) (xy 320.8655 -123.571) (xy 321.2465 -123.571) (xy 321.2465 -123.063)
				)
			)
		)
		(zone
			(layer "F.Cu")
			(hatch none 0.5)
			(connect_pads
				(clearance 0)
			)
			(min_thickness 0.25)
			(keepout
				(tracks not_allowed)
				(vias allowed)
				(pads allowed)
				(copperpour not_allowed)
				(footprints allowed)
			)
			(placement
				(enabled no)
				(sheetname "")
			)
			(fill
				(thermal_gap 0.5)
				(thermal_bridge_width 0.5)
				(island_removal_mode 0)
			)
			(polygon
				(pts
					(xy 321.2465 -123.063) (xy 321.2465 -123.571) (xy 320.8655 -123.571) (xy 320.8655 -123.063)
				)
			)
		)
	)
)
